# T6G (Grand Teton) — schematic netlist excerpt (pin names and nets, part order shuffled) for the footprints in the layout excerpt that follows; sources: Cadence DE-HDL packaged netlist, KiCad conversion of 04192023_DAF0TMB3IC0_F0TG_MB_C_brd_V02_OCP.brd

R3909  Q_RES  33.2 1% CHIP  pkg 0402LF  page 262 : A = SMB_SML1_PMBUS_HSC_SCL ; B = SMB_SML1_PMBUS_HSC_L_SCL
C2321  Q_CAP  22UF 4V 20% X6S  pkg C0402  page 73 : A = PVDDCR_CPU0_P1 ; B = GND

(kicad_pcb
	(version 20260206)
	(generator "pcbnew")
	(generator_version "10.0")
	(general
		(thickness 1.6)
		(legacy_teardrops no)
	)
	(paper "A4")
	(title_block
		(title "04192023_DAF0TMB3IC0_F0TG_MB_C_brd_V02_OCP.brd")
		(comment 1 "Grand Teton / footprints 5645-5646 of 8354")
	)
	(layers
		(0 "F.Cu" signal "TOP")
		(4 "In1.Cu" signal "GND")
		(6 "In2.Cu" signal "IN1")
		(8 "In3.Cu" signal "GND1")
		(10 "In4.Cu" signal "IN2")
		(12 "In5.Cu" signal "GND2")
		(14 "In6.Cu" signal "IN3")
		(16 "In7.Cu" signal "GND3")
		(18 "In8.Cu" signal "VCC")
		(20 "In9.Cu" signal "VCC1")
		(22 "In10.Cu" signal "GND4")
		(24 "In11.Cu" signal "IN4")
		(26 "In12.Cu" signal "GND5")
		(28 "In13.Cu" signal "IN5")
		(30 "In14.Cu" signal "GND6")
		(32 "In15.Cu" signal "IN6")
		(34 "In16.Cu" signal "GND7")
		(2 "B.Cu" signal "BOTTOM")
		(9 "F.Adhes" user "F.Adhesive")
		(11 "B.Adhes" user "B.Adhesive")
		(13 "F.Paste" user "Package Geometry/Pastemask Top")
		(15 "B.Paste" user "Package Geometry/Pastemask Bottom")
		(5 "F.SilkS" user "Ref Des/Silkscreen Top")
		(7 "B.SilkS" user "Ref Des/Silkscreen Bottom")
		(1 "F.Mask" user "Board Geometry/Soldermask Top")
		(3 "B.Mask" user "Board Geometry/Soldermask Bottom")
		(17 "Dwgs.User" user "User.Drawings")
		(19 "Cmts.User" user "User.Comments")
		(21 "Eco1.User" user "User.Eco1")
		(23 "Eco2.User" user "User.Eco2")
		(25 "Edge.Cuts" user "Board Geometry/Outline")
		(27 "Margin" user)
		(31 "F.CrtYd" user "Package Geometry/Place Bound Top")
		(29 "B.CrtYd" user "Package Geometry/Place Bound Bottom")
		(35 "F.Fab" user "Ref Des/Assembly Top")
		(33 "B.Fab" user "Ref Des/Assembly Bottom")
	)
	(footprint ""
		(layer "B.Cu")
		(at 182.294276 -407.219912 90)
		(property "Reference" "R3909"
			(at 0 0 90)
			(layer "B.SilkS")
			(hide yes)
			(effects
				(font
					(size 1.27 1.27)
				)
				(justify mirror)
			)
		)
		(property "Value" ""
			(at 0 0 90)
			(layer "B.Fab")
			(effects
				(font
					(size 1.27 1.27)
				)
				(justify mirror)
			)
		)
		(duplicate_pad_numbers_are_jumpers no)
		(fp_line
			(start 0.7874 -0.4064)
			(end -0.7874 -0.4064)
			(stroke
				(width 0.1524)
				(type default)
			)
			(layer "B.SilkS")
		)
		(fp_line
			(start -0.7874 -0.4064)
			(end -0.7874 0.4064)
			(stroke
				(width 0.1524)
				(type default)
			)
			(layer "B.SilkS")
		)
		(fp_line
			(start 0.7874 0.4064)
			(end 0.7874 -0.4064)
			(stroke
				(width 0.1524)
				(type default)
			)
			(layer "B.SilkS")
		)
		(fp_line
			(start -0.7874 0.4064)
			(end 0.7874 0.4064)
			(stroke
				(width 0.1524)
				(type default)
			)
			(layer "B.SilkS")
		)
		(fp_line
			(start 0.67945 -0.305054)
			(end 0.12065 -0.305054)
			(stroke
				(width 0.1)
				(type default)
			)
			(layer "B.Fab")
		)
		(fp_line
			(start 0.12065 -0.305054)
			(end 0.12065 -0.2794)
			(stroke
				(width 0.1)
				(type default)
			)
			(layer "B.Fab")
		)
		(fp_line
			(start -0.12065 -0.3048)
			(end -0.67945 -0.3048)
			(stroke
				(width 0.1)
				(type default)
			)
			(layer "B.Fab")
		)
		(fp_line
			(start -0.67945 -0.3048)
			(end -0.67945 0.3048)
			(stroke
				(width 0.1)
				(type default)
			)
			(layer "B.Fab")
		)
		(fp_line
			(start 0.12065 -0.2794)
			(end -0.12065 -0.2794)
			(stroke
				(width 0.1)
				(type default)
			)
			(layer "B.Fab")
		)
		(fp_line
			(start -0.12065 -0.2794)
			(end -0.12065 -0.3048)
			(stroke
				(width 0.1)
				(type default)
			)
			(layer "B.Fab")
		)
		(fp_line
			(start 0.12065 0.2794)
			(end 0.12065 0.3048)
			(stroke
				(width 0.1)
				(type default)
			)
			(layer "B.Fab")
		)
		(fp_line
			(start -0.120396 0.2794)
			(end 0.12065 0.2794)
			(stroke
				(width 0.1)
				(type default)
			)
			(layer "B.Fab")
		)
		(fp_line
			(start 0.67945 0.3048)
			(end 0.67945 -0.305054)
			(stroke
				(width 0.1)
				(type default)
			)
			(layer "B.Fab")
		)
		(fp_line
			(start 0.12065 0.3048)
			(end 0.67945 0.3048)
			(stroke
				(width 0.1)
				(type default)
			)
			(layer "B.Fab")
		)
		(fp_line
			(start -0.120396 0.3048)
			(end -0.120396 0.2794)
			(stroke
				(width 0.1)
				(type default)
			)
			(layer "B.Fab")
		)
		(fp_line
			(start -0.67945 0.3048)
			(end -0.120396 0.3048)
			(stroke
				(width 0.1)
				(type default)
			)
			(layer "B.Fab")
		)
		(pad "1" smd circle
			(at 0.40005 0 270)
			(size 0 0)
			(layers "B.Cu" "B.Mask" "B.Paste")
			(net "SMB_SML1_PMBUS_HSC_SCL")
		)
		(pad "2" smd circle
			(at -0.40005 0 270)
			(size 0 0)
			(layers "B.Cu" "B.Mask" "B.Paste")
			(net "SMB_SML1_PMBUS_HSC_L_SCL")
		)
	)
	(footprint ""
		(layer "B.Cu")
		(at 111.800386 -246.066564 90)
		(property "Reference" "C2321"
			(at 0 0 90)
			(layer "B.SilkS")
			(hide yes)
			(effects
				(font
					(size 1.27 1.27)
				)
				(justify mirror)
			)
		)
		(property "Value" ""
			(at 0 0 90)
			(layer "B.Fab")
			(effects
				(font
					(size 1.27 1.27)
				)
				(justify mirror)
			)
		)
		(duplicate_pad_numbers_are_jumpers no)
		(fp_line
			(start 0.7874 -0.4064)
			(end -0.7874 -0.4064)
			(stroke
				(width 0.1524)
				(type default)
			)
			(layer "B.SilkS")
		)
		(fp_line
			(start -0.7874 -0.4064)
			(end -0.7874 0.4064)
			(stroke
				(width 0.1524)
				(type default)
			)
			(layer "B.SilkS")
		)
		(fp_line
			(start 0.7874 0.4064)
			(end 0.7874 -0.4064)
			(stroke
				(width 0.1524)
				(type default)
			)
			(layer "B.SilkS")
		)
		(fp_line
			(start -0.7874 0.4064)
			(end 0.7874 0.4064)
			(stroke
				(width 0.1524)
				(type default)
			)
			(layer "B.SilkS")
		)
		(fp_line
			(start 0.67945 -0.305054)
			(end 0.12065 -0.305054)
			(stroke
				(width 0.1)
				(type default)
			)
			(layer "B.Fab")
		)
		(fp_line
			(start 0.12065 -0.305054)
			(end 0.12065 -0.2794)
			(stroke
				(width 0.1)
				(type default)
			)
			(layer "B.Fab")
		)
		(fp_line
			(start -0.12065 -0.3048)
			(end -0.67945 -0.3048)
			(stroke
				(width 0.1)
				(type default)
			)
			(layer "B.Fab")
		)
		(fp_line
			(start -0.67945 -0.3048)
			(end -0.67945 0.3048)
			(stroke
				(width 0.1)
				(type default)
			)
			(layer "B.Fab")
		)
		(fp_line
			(start 0.12065 -0.2794)
			(end -0.12065 -0.2794)
			(stroke
				(width 0.1)
				(type default)
			)
			(layer "B.Fab")
		)
		(fp_line
			(start -0.12065 -0.2794)
			(end -0.12065 -0.3048)
			(stroke
				(width 0.1)
				(type default)
			)
			(layer "B.Fab")
		)
		(fp_line
			(start 0.12065 0.2794)
			(end 0.12065 0.3048)
			(stroke
				(width 0.1)
				(type default)
			)
			(layer "B.Fab")
		)
		(fp_line
			(start -0.120396 0.2794)
			(end 0.12065 0.2794)
			(stroke
				(width 0.1)
				(type default)
			)
			(layer "B.Fab")
		)
		(fp_line
			(start 0.67945 0.3048)
			(end 0.67945 -0.305054)
			(stroke
				(width 0.1)
				(type default)
			)
			(layer "B.Fab")
		)
		(fp_line
			(start 0.12065 0.3048)
			(end 0.67945 0.3048)
			(stroke
				(width 0.1)
				(type default)
			)
			(layer "B.Fab")
		)
		(fp_line
			(start -0.120396 0.3048)
			(end -0.120396 0.2794)
			(stroke
				(width 0.1)
				(type default)
			)
			(layer "B.Fab")
		)
		(fp_line
			(start -0.67945 0.3048)
			(end -0.120396 0.3048)
			(stroke
				(width 0.1)
				(type default)
			)
			(layer "B.Fab")
		)
		(pad "1" smd circle
			(at 0.40005 0 270)
			(size 0 0)
			(layers "B.Cu" "B.Mask" "B.Paste")
			(net "PVDDCR_CPU0_P1")
		)
		(pad "2" smd circle
			(at -0.40005 0 270)
			(size 0 0)
			(layers "B.Cu" "B.Mask" "B.Paste")
			(net "GND")
		)
	)
)
